(kicad_pcb
	(version 20260206)
	(generator "pcbnew")
	(generator_version "10.0")
	(general
		(thickness 1.6)
		(legacy_teardrops no)
	)
	(paper "A4")
	(title_block
		(title "baseboard — 13948-1b.1110WZS1818.brd")
		(comment 1 "Honey Badger (Wiwynn) / footprints 969-976 of 2523")
	)
	(layers
		(0 "F.Cu" signal "TOP")
		(4 "In1.Cu" signal "L2GND")
		(6 "In2.Cu" signal "L3")
		(8 "In3.Cu" signal "L4VCC")
		(10 "In4.Cu" signal "L5VCC")
		(12 "In5.Cu" signal "L6")
		(14 "In6.Cu" signal "L7GND")
		(2 "B.Cu" signal "BOTTOM")
		(9 "F.Adhes" user "F.Adhesive")
		(11 "B.Adhes" user "B.Adhesive")
		(13 "F.Paste" user "Package Geometry/Pastemask Top")
		(15 "B.Paste" user "Package Geometry/Pastemask Bottom")
		(5 "F.SilkS" user "Ref Des/Silkscreen Top")
		(7 "B.SilkS" user "Ref Des/Silkscreen Bottom")
		(1 "F.Mask" user "Board Geometry/Soldermask Top")
		(3 "B.Mask" user "Board Geometry/Soldermask Bottom")
		(17 "Dwgs.User" user "User.Drawings")
		(19 "Cmts.User" user "User.Comments")
		(21 "Eco1.User" user "User.Eco1")
		(23 "Eco2.User" user "User.Eco2")
		(25 "Edge.Cuts" user "Board Geometry/Outline")
		(27 "Margin" user)
		(31 "F.CrtYd" user "Package Geometry/Place Bound Top")
		(29 "B.CrtYd" user "Package Geometry/Place Bound Bottom")
		(35 "F.Fab" user "Ref Des/Assembly Top")
		(33 "B.Fab" user "Ref Des/Assembly Bottom")
	)
	(footprint ""
		(layer "F.Cu")
		(at 204.089 -216.154 -90)
		(property "Reference" "R1585"
			(at 0 0 270)
			(layer "F.SilkS")
			(hide yes)
			(effects
				(font
					(size 1.27 1.27)
				)
			)
		)
		(property "Value" "4K7R2F-GP"
			(at 0.064008 -3.993896 270)
			(unlocked yes)
			(layer "F.Fab")
			(hide yes)
			(effects
				(font
					(size 1.016 1.016)
					(thickness 0.1524)
				)
			)
		)
		(property "Device Type" "R402H16"
			(at 0.064008 -5.517896 270)
			(unlocked yes)
			(layer "F.Fab")
			(hide yes)
			(effects
				(font
					(size 1.016 1.016)
					(thickness 0.1524)
				)
			)
		)
		(duplicate_pad_numbers_are_jumpers no)
		(fp_line
			(start -0.508 -0.9398)
			(end -0.508 0.9398)
			(stroke
				(width 0.1524)
				(type default)
			)
			(layer "F.SilkS")
		)
		(fp_line
			(start 0.508 -0.9398)
			(end -0.508 -0.9398)
			(stroke
				(width 0.1524)
				(type default)
			)
			(layer "F.SilkS")
		)
		(fp_rect
			(start -0.508 0.9398)
			(end 0.508 -0.9398)
			(stroke
				(width 0)
				(type default)
			)
			(fill no)
			(layer "F.CrtYd")
		)
		(fp_rect
			(start -0.508 0.9398)
			(end 0.508 -0.9398)
			(stroke
				(width 0)
				(type default)
			)
			(fill no)
			(layer "F.Fab")
		)
		(pad "1" smd custom
			(at 0 -0.4445 270)
			(size 0.1397 0.1397)
			(layers "F.Cu" "F.Mask" "F.Paste")
			(net "P3V3_STBY")
			(options
				(clearance outline)
				(anchor circle)
			)
			(primitives
				(gr_poly
					(pts
						(arc
							(start -0.1778 -0.2794)
							(mid -0.249642 -0.249642)
							(end -0.2794 -0.1778)
						)
						(arc
							(start -0.2794 0.1778)
							(mid -0.249642 0.249642)
							(end -0.1778 0.2794)
						)
						(arc
							(start 0.1778 0.2794)
							(mid 0.249642 0.249642)
							(end 0.2794 0.1778)
						)
						(arc
							(start 0.2794 -0.1778)
							(mid 0.249642 -0.249642)
							(end 0.1778 -0.2794)
						)
					)
					(width 0)
					(fill yes)
				)
			)
		)
		(pad "2" smd custom
			(at 0 0.4445 270)
			(size 0.1397 0.1397)
			(layers "F.Cu" "F.Mask" "F.Paste")
			(net "CPU_EXP_RESET_N")
			(options
				(clearance outline)
				(anchor circle)
			)
			(primitives
				(gr_poly
					(pts
						(arc
							(start -0.1778 -0.2794)
							(mid -0.249642 -0.249642)
							(end -0.2794 -0.1778)
						)
						(arc
							(start -0.2794 0.1778)
							(mid -0.249642 0.249642)
							(end -0.1778 0.2794)
						)
						(arc
							(start 0.1778 0.2794)
							(mid 0.249642 0.249642)
							(end 0.2794 0.1778)
						)
						(arc
							(start 0.2794 -0.1778)
							(mid 0.249642 -0.249642)
							(end 0.1778 -0.2794)
						)
					)
					(width 0)
					(fill yes)
				)
			)
		)
	)
	(footprint ""
		(layer "F.Cu")
		(at 60.071 -211.074 180)
		(property "Reference" "R688"
			(at 0 0 180)
			(layer "F.SilkS")
			(hide yes)
			(effects
				(font
					(size 1.27 1.27)
				)
			)
		)
		(property "Value" "10KR2J-3-GP"
			(at 0.064008 -3.993896 180)
			(unlocked yes)
			(layer "F.Fab")
			(hide yes)
			(effects
				(font
					(size 1.016 1.016)
					(thickness 0.1524)
				)
			)
		)
		(property "Device Type" "R402H16"
			(at 0.064008 -5.517896 180)
			(unlocked yes)
			(layer "F.Fab")
			(hide yes)
			(effects
				(font
					(size 1.016 1.016)
					(thickness 0.1524)
				)
			)
		)
		(duplicate_pad_numbers_are_jumpers no)
		(fp_line
			(start 0.508 -0.9398)
			(end -0.508 -0.9398)
			(stroke
				(width 0.1524)
				(type default)
			)
			(layer "F.SilkS")
		)
		(fp_line
			(start -0.508 -0.9398)
			(end -0.508 0.9398)
			(stroke
				(width 0.1524)
				(type default)
			)
			(layer "F.SilkS")
		)
		(fp_rect
			(start -0.508 0.9398)
			(end 0.508 -0.9398)
			(stroke
				(width 0)
				(type default)
			)
			(fill no)
			(layer "F.CrtYd")
		)
		(fp_rect
			(start -0.508 0.9398)
			(end 0.508 -0.9398)
			(stroke
				(width 0)
				(type default)
			)
			(fill no)
			(layer "F.Fab")
		)
		(pad "1" smd custom
			(at 0 -0.4445 180)
			(size 0.1397 0.1397)
			(layers "F.Cu" "F.Mask" "F.Paste")
			(net "GND")
			(options
				(clearance outline)
				(anchor circle)
			)
			(primitives
				(gr_poly
					(pts
						(arc
							(start -0.1778 -0.2794)
							(mid -0.249642 -0.249642)
							(end -0.2794 -0.1778)
						)
						(arc
							(start -0.2794 0.1778)
							(mid -0.249642 0.249642)
							(end -0.1778 0.2794)
						)
						(arc
							(start 0.1778 0.2794)
							(mid 0.249642 0.249642)
							(end 0.2794 0.1778)
						)
						(arc
							(start 0.2794 -0.1778)
							(mid 0.249642 -0.249642)
							(end 0.1778 -0.2794)
						)
					)
					(width 0)
					(fill yes)
				)
			)
		)
		(pad "2" smd custom
			(at 0 0.4445 180)
			(size 0.1397 0.1397)
			(layers "F.Cu" "F.Mask" "F.Paste")
			(net "MB0_RETRY_R")
			(options
				(clearance outline)
				(anchor circle)
			)
			(primitives
				(gr_poly
					(pts
						(arc
							(start -0.1778 -0.2794)
							(mid -0.249642 -0.249642)
							(end -0.2794 -0.1778)
						)
						(arc
							(start -0.2794 0.1778)
							(mid -0.249642 0.249642)
							(end -0.1778 0.2794)
						)
						(arc
							(start 0.1778 0.2794)
							(mid 0.249642 0.249642)
							(end 0.2794 0.1778)
						)
						(arc
							(start 0.2794 -0.1778)
							(mid 0.249642 -0.249642)
							(end 0.1778 -0.2794)
						)
					)
					(width 0)
					(fill yes)
				)
			)
		)
	)
	(footprint ""
		(layer "F.Cu")
		(at 323.342 -179.705 180)
		(property "Reference" "C8086"
			(at 0 0 180)
			(layer "F.SilkS")
			(hide yes)
			(effects
				(font
					(size 1.27 1.27)
				)
			)
		)
		(property "Value" "SCD1U25V2KX-2-GP"
			(at 1.1811 -2.7051 180)
			(unlocked yes)
			(layer "F.Fab")
			(hide yes)
			(effects
				(font
					(size 1.016 1.016)
					(thickness 0.1524)
				)
			)
		)
		(property "Device Type" "C402H22"
			(at 1.1811 -4.2291 180)
			(unlocked yes)
			(layer "F.Fab")
			(hide yes)
			(effects
				(font
					(size 1.016 1.016)
					(thickness 0.1524)
				)
			)
		)
		(duplicate_pad_numbers_are_jumpers no)
		(fp_rect
			(start -0.4318 0.9525)
			(end 0.4318 -0.9525)
			(stroke
				(width 0)
				(type default)
			)
			(fill no)
			(layer "F.CrtYd")
		)
		(fp_rect
			(start -0.4318 0.9525)
			(end 0.4318 -0.9525)
			(stroke
				(width 0)
				(type default)
			)
			(fill no)
			(layer "F.Fab")
		)
		(pad "1" smd custom
			(at 0 -0.4445 180)
			(size 0.1524 0.1524)
			(layers "F.Cu" "F.Mask" "F.Paste")
			(net "ADC_P1V5_C")
			(options
				(clearance outline)
				(anchor circle)
			)
			(primitives
				(gr_poly
					(pts
						(arc
							(start 0.3048 -0.2032)
							(mid 0.275042 -0.275042)
							(end 0.2032 -0.3048)
						)
						(arc
							(start -0.2032 -0.3048)
							(mid -0.275042 -0.275042)
							(end -0.3048 -0.2032)
						)
						(arc
							(start -0.3048 0.2032)
							(mid -0.275042 0.275042)
							(end -0.2032 0.3048)
						)
						(arc
							(start 0.2032 0.3048)
							(mid 0.275042 0.275042)
							(end 0.3048 0.2032)
						)
					)
					(width 0)
					(fill yes)
				)
			)
		)
		(pad "2" smd custom
			(at 0 0.4445 180)
			(size 0.1524 0.1524)
			(layers "F.Cu" "F.Mask" "F.Paste")
			(net "GND")
			(options
				(clearance outline)
				(anchor circle)
			)
			(primitives
				(gr_poly
					(pts
						(arc
							(start 0.3048 -0.2032)
							(mid 0.275042 -0.275042)
							(end 0.2032 -0.3048)
						)
						(arc
							(start -0.2032 -0.3048)
							(mid -0.275042 -0.275042)
							(end -0.3048 -0.2032)
						)
						(arc
							(start -0.3048 0.2032)
							(mid -0.275042 0.275042)
							(end -0.2032 0.3048)
						)
						(arc
							(start 0.2032 0.3048)
							(mid 0.275042 0.275042)
							(end 0.3048 0.2032)
						)
					)
					(width 0)
					(fill yes)
				)
			)
		)
	)
	(footprint ""
		(layer "F.Cu")
		(at 348.390718 -151.869648 -90)
		(property "Reference" "R452"
			(at 0 0 270)
			(layer "F.SilkS")
			(hide yes)
			(effects
				(font
					(size 1.27 1.27)
				)
			)
		)
		(property "Value" "0R2J-2-GP"
			(at 0.064008 -3.993896 270)
			(unlocked yes)
			(layer "F.Fab")
			(hide yes)
			(effects
				(font
					(size 1.016 1.016)
					(thickness 0.1524)
				)
			)
		)
		(property "Device Type" "R402H16"
			(at 0.064008 -5.517896 270)
			(unlocked yes)
			(layer "F.Fab")
			(hide yes)
			(effects
				(font
					(size 1.016 1.016)
					(thickness 0.1524)
				)
			)
		)
		(duplicate_pad_numbers_are_jumpers no)
		(fp_line
			(start -0.508 -0.9398)
			(end -0.508 0.9398)
			(stroke
				(width 0.1524)
				(type default)
			)
			(layer "F.SilkS")
		)
		(fp_line
			(start 0.508 -0.9398)
			(end -0.508 -0.9398)
			(stroke
				(width 0.1524)
				(type default)
			)
			(layer "F.SilkS")
		)
		(fp_rect
			(start -0.508 0.9398)
			(end 0.508 -0.9398)
			(stroke
				(width 0)
				(type default)
			)
			(fill no)
			(layer "F.CrtYd")
		)
		(fp_rect
			(start -0.508 0.9398)
			(end 0.508 -0.9398)
			(stroke
				(width 0)
				(type default)
			)
			(fill no)
			(layer "F.Fab")
		)
		(pad "1" smd custom
			(at 0 -0.4445 270)
			(size 0.1397 0.1397)
			(layers "F.Cu" "F.Mask" "F.Paste")
			(net "BMC_USB1_HDN")
			(options
				(clearance outline)
				(anchor circle)
			)
			(primitives
				(gr_poly
					(pts
						(arc
							(start -0.1778 -0.2794)
							(mid -0.249642 -0.249642)
							(end -0.2794 -0.1778)
						)
						(arc
							(start -0.2794 0.1778)
							(mid -0.249642 0.249642)
							(end -0.1778 0.2794)
						)
						(arc
							(start 0.1778 0.2794)
							(mid 0.249642 0.249642)
							(end 0.2794 0.1778)
						)
						(arc
							(start 0.2794 -0.1778)
							(mid 0.249642 -0.249642)
							(end 0.1778 -0.2794)
						)
					)
					(width 0)
					(fill yes)
				)
			)
		)
		(pad "2" smd custom
			(at 0 0.4445 270)
			(size 0.1397 0.1397)
			(layers "F.Cu" "F.Mask" "F.Paste")
			(net "USB_P3_DN")
			(options
				(clearance outline)
				(anchor circle)
			)
			(primitives
				(gr_poly
					(pts
						(arc
							(start -0.1778 -0.2794)
							(mid -0.249642 -0.249642)
							(end -0.2794 -0.1778)
						)
						(arc
							(start -0.2794 0.1778)
							(mid -0.249642 0.249642)
							(end -0.1778 0.2794)
						)
						(arc
							(start 0.1778 0.2794)
							(mid 0.249642 0.249642)
							(end 0.2794 0.1778)
						)
						(arc
							(start 0.2794 -0.1778)
							(mid 0.249642 -0.249642)
							(end 0.1778 -0.2794)
						)
					)
					(width 0)
					(fill yes)
				)
			)
		)
	)
	(footprint ""
		(layer "F.Cu")
		(at 52.0446 -231.01554)
		(property "Reference" "C300"
			(at 0 0 0)
			(layer "F.SilkS")
			(hide yes)
			(effects
				(font
					(size 1.27 1.27)
				)
			)
		)
		(property "Value" "SC22U25V5MX-GP"
			(at -0.0762 -6.1214 0)
			(unlocked yes)
			(layer "F.Fab")
			(hide yes)
			(effects
				(font
					(size 1.016 1.016)
					(thickness 0.1524)
				)
			)
		)
		(property "Device Type" "C805H58"
			(at -0.0762 -8.1534 0)
			(unlocked yes)
			(layer "F.Fab")
			(hide yes)
			(effects
				(font
					(size 1.016 1.016)
					(thickness 0.1524)
				)
			)
		)
		(duplicate_pad_numbers_are_jumpers no)
		(fp_line
			(start 0.635 0)
			(end -0.635 0)
			(stroke
				(width 0.508)
				(type default)
			)
			(layer "F.SilkS")
		)
		(fp_rect
			(start -0.9652 1.778)
			(end 0.9652 -1.778)
			(stroke
				(width 0)
				(type default)
			)
			(fill no)
			(layer "F.CrtYd")
		)
		(fp_poly
			(pts
				(xy -0.9652 -1.778) (xy 0.9652 -1.778) (xy 0.9652 1.778) (xy -0.9652 1.778)
			)
			(stroke
				(width 0)
				(type default)
			)
			(fill no)
			(layer "F.Fab")
		)
		(pad "1" smd rect
			(at 0 -0.9652)
			(size 1.397 1.143)
			(layers "F.Cu" "F.Mask" "F.Paste")
			(net "P12V_PCIE")
		)
		(pad "2" smd rect
			(at 0 0.9652)
			(size 1.397 1.143)
			(layers "F.Cu" "F.Mask" "F.Paste")
			(net "GND")
		)
	)
	(footprint ""
		(layer "F.Cu")
		(at 266.754864 -228.845872 90)
		(property "Reference" "PC90"
			(at 0 0 90)
			(layer "F.SilkS")
			(hide yes)
			(effects
				(font
					(size 1.27 1.27)
				)
			)
		)
		(property "Value" "SCD1U16V2KX-3GP"
			(at 1.1811 -2.7051 90)
			(unlocked yes)
			(layer "F.Fab")
			(hide yes)
			(effects
				(font
					(size 1.016 1.016)
					(thickness 0.1524)
				)
			)
		)
		(property "Device Type" "C402H22"
			(at 1.1811 -4.2291 90)
			(unlocked yes)
			(layer "F.Fab")
			(hide yes)
			(effects
				(font
					(size 1.016 1.016)
					(thickness 0.1524)
				)
			)
		)
		(duplicate_pad_numbers_are_jumpers no)
		(fp_rect
			(start -0.4318 0.9525)
			(end 0.4318 -0.9525)
			(stroke
				(width 0)
				(type default)
			)
			(fill no)
			(layer "F.CrtYd")
		)
		(fp_rect
			(start -0.4318 0.9525)
			(end 0.4318 -0.9525)
			(stroke
				(width 0)
				(type default)
			)
			(fill no)
			(layer "F.Fab")
		)
		(pad "1" smd custom
			(at 0 -0.4445 90)
			(size 0.1524 0.1524)
			(layers "F.Cu" "F.Mask" "F.Paste")
			(net "TPS74801_P1V26_STBY_IN")
			(options
				(clearance outline)
				(anchor circle)
			)
			(primitives
				(gr_poly
					(pts
						(arc
							(start 0.3048 -0.2032)
							(mid 0.275042 -0.275042)
							(end 0.2032 -0.3048)
						)
						(arc
							(start -0.2032 -0.3048)
							(mid -0.275042 -0.275042)
							(end -0.3048 -0.2032)
						)
						(arc
							(start -0.3048 0.2032)
							(mid -0.275042 0.275042)
							(end -0.2032 0.3048)
						)
						(arc
							(start 0.2032 0.3048)
							(mid 0.275042 0.275042)
							(end 0.3048 0.2032)
						)
					)
					(width 0)
					(fill yes)
				)
			)
		)
		(pad "2" smd custom
			(at 0 0.4445 90)
			(size 0.1524 0.1524)
			(layers "F.Cu" "F.Mask" "F.Paste")
			(net "GND")
			(options
				(clearance outline)
				(anchor circle)
			)
			(primitives
				(gr_poly
					(pts
						(arc
							(start 0.3048 -0.2032)
							(mid 0.275042 -0.275042)
							(end 0.2032 -0.3048)
						)
						(arc
							(start -0.2032 -0.3048)
							(mid -0.275042 -0.275042)
							(end -0.3048 -0.2032)
						)
						(arc
							(start -0.3048 0.2032)
							(mid -0.275042 0.275042)
							(end -0.2032 0.3048)
						)
						(arc
							(start 0.2032 0.3048)
							(mid 0.275042 0.275042)
							(end 0.3048 0.2032)
						)
					)
					(width 0)
					(fill yes)
				)
			)
		)
	)
	(footprint ""
		(layer "F.Cu")
		(at 335.407 -211.455 180)
		(property "Reference" "R5304"
			(at 0 0 180)
			(layer "F.SilkS")
			(hide yes)
			(effects
				(font
					(size 1.27 1.27)
				)
			)
		)
		(property "Value" "0R2J-2-GP"
			(at 0.064008 -3.993896 180)
			(unlocked yes)
			(layer "F.Fab")
			(hide yes)
			(effects
				(font
					(size 1.016 1.016)
					(thickness 0.1524)
				)
			)
		)
		(property "Device Type" "R402H16"
			(at 0.064008 -5.517896 180)
			(unlocked yes)
			(layer "F.Fab")
			(hide yes)
			(effects
				(font
					(size 1.016 1.016)
					(thickness 0.1524)
				)
			)
		)
		(duplicate_pad_numbers_are_jumpers no)
		(fp_line
			(start 0.508 -0.9398)
			(end -0.508 -0.9398)
			(stroke
				(width 0.1524)
				(type default)
			)
			(layer "F.SilkS")
		)
		(fp_line
			(start -0.508 -0.9398)
			(end -0.508 0.9398)
			(stroke
				(width 0.1524)
				(type default)
			)
			(layer "F.SilkS")
		)
		(fp_rect
			(start -0.508 0.9398)
			(end 0.508 -0.9398)
			(stroke
				(width 0)
				(type default)
			)
			(fill no)
			(layer "F.CrtYd")
		)
		(fp_rect
			(start -0.508 0.9398)
			(end 0.508 -0.9398)
			(stroke
				(width 0)
				(type default)
			)
			(fill no)
			(layer "F.Fab")
		)
		(pad "1" smd custom
			(at 0 -0.4445 180)
			(size 0.1397 0.1397)
			(layers "F.Cu" "F.Mask" "F.Paste")
			(net "EEPROM_SDA")
			(options
				(clearance outline)
				(anchor circle)
			)
			(primitives
				(gr_poly
					(pts
						(arc
							(start -0.1778 -0.2794)
							(mid -0.249642 -0.249642)
							(end -0.2794 -0.1778)
						)
						(arc
							(start -0.2794 0.1778)
							(mid -0.249642 0.249642)
							(end -0.1778 0.2794)
						)
						(arc
							(start 0.1778 0.2794)
							(mid 0.249642 0.249642)
							(end 0.2794 0.1778)
						)
						(arc
							(start 0.2794 -0.1778)
							(mid 0.249642 -0.249642)
							(end 0.1778 -0.2794)
						)
					)
					(width 0)
					(fill yes)
				)
			)
		)
		(pad "2" smd custom
			(at 0 0.4445 180)
			(size 0.1397 0.1397)
			(layers "F.Cu" "F.Mask" "F.Paste")
			(net "BMC_I2C_SDA_10")
			(options
				(clearance outline)
				(anchor circle)
			)
			(primitives
				(gr_poly
					(pts
						(arc
							(start -0.1778 -0.2794)
							(mid -0.249642 -0.249642)
							(end -0.2794 -0.1778)
						)
						(arc
							(start -0.2794 0.1778)
							(mid -0.249642 0.249642)
							(end -0.1778 0.2794)
						)
						(arc
							(start 0.1778 0.2794)
							(mid 0.249642 0.249642)
							(end 0.2794 0.1778)
						)
						(arc
							(start 0.2794 -0.1778)
							(mid 0.249642 -0.249642)
							(end 0.1778 -0.2794)
						)
					)
					(width 0)
					(fill yes)
				)
			)
		)
	)
	(footprint ""
		(layer "F.Cu")
		(at 293.996872 -223.592136 180)
		(property "Reference" "PC84"
			(at 0 0 180)
			(layer "F.SilkS")
			(hide yes)
			(effects
				(font
					(size 1.27 1.27)
				)
			)
		)
		(property "Value" "SC10U6D3V5KX-1GP"
			(at -0.0762 -6.1214 180)
			(unlocked yes)
			(layer "F.Fab")
			(hide yes)
			(effects
				(font
					(size 1.016 1.016)
					(thickness 0.1524)
				)
			)
		)
		(property "Device Type" "C805H54"
			(at -0.0762 -8.1534 180)
			(unlocked yes)
			(layer "F.Fab")
			(hide yes)
			(effects
				(font
					(size 1.016 1.016)
					(thickness 0.1524)
				)
			)
		)
		(duplicate_pad_numbers_are_jumpers no)
		(fp_line
			(start 0.635 0)
			(end -0.635 0)
			(stroke
				(width 0.508)
				(type default)
			)
			(layer "F.SilkS")
		)
		(fp_rect
			(start -0.9652 1.778)
			(end 0.9652 -1.778)
			(stroke
				(width 0)
				(type default)
			)
			(fill no)
			(layer "F.CrtYd")
		)
		(fp_poly
			(pts
				(xy -0.9652 -1.778) (xy 0.9652 -1.778) (xy 0.9652 1.778) (xy -0.9652 1.778)
			)
			(stroke
				(width 0)
				(type default)
			)
			(fill no)
			(layer "F.Fab")
		)
		(pad "1" smd rect
			(at 0 -0.9652 180)
			(size 1.397 1.143)
			(layers "F.Cu" "F.Mask" "F.Paste")
			(net "TPS74801_1V53_STBY_OUT")
		)
		(pad "2" smd rect
			(at 0 0.9652 180)
			(size 1.397 1.143)
			(layers "F.Cu" "F.Mask" "F.Paste")
			(net "GND")
		)
	)
)
